# T6G (Grand Teton) — schematic netlist excerpt (pin names and nets, part order shuffled) for the footprints in the layout excerpt that follows; sources: Cadence DE-HDL packaged netlist, KiCad conversion of 04192023_DAF0TMB3IC0_F0TG_MB_C_brd_V02_OCP.brd

R73  Q_RES  22 1% CHIP  pkg 0402LF  page 132 : A = NCSI_BMC_RXD1_R ; B = RMII_OCP_BMC_RXD_1
R6270  Q_RES  0 5% CHIP  pkg 0402LF  page 178 : A = P3V3_AUX_CPU0_USB2_AVDD33 ; B = USB_HUB2_TI_PWRCTL3_MRP_VDD33

(kicad_pcb
	(version 20260206)
	(generator "pcbnew")
	(generator_version "10.0")
	(general
		(thickness 1.6)
		(legacy_teardrops no)
	)
	(paper "A4")
	(title_block
		(title "04192023_DAF0TMB3IC0_F0TG_MB_C_brd_V02_OCP.brd")
		(comment 1 "Grand Teton / footprints 2104-2105 of 8354")
	)
	(layers
		(0 "F.Cu" signal "TOP")
		(4 "In1.Cu" signal "GND")
		(6 "In2.Cu" signal "IN1")
		(8 "In3.Cu" signal "GND1")
		(10 "In4.Cu" signal "IN2")
		(12 "In5.Cu" signal "GND2")
		(14 "In6.Cu" signal "IN3")
		(16 "In7.Cu" signal "GND3")
		(18 "In8.Cu" signal "VCC")
		(20 "In9.Cu" signal "VCC1")
		(22 "In10.Cu" signal "GND4")
		(24 "In11.Cu" signal "IN4")
		(26 "In12.Cu" signal "GND5")
		(28 "In13.Cu" signal "IN5")
		(30 "In14.Cu" signal "GND6")
		(32 "In15.Cu" signal "IN6")
		(34 "In16.Cu" signal "GND7")
		(2 "B.Cu" signal "BOTTOM")
		(9 "F.Adhes" user "F.Adhesive")
		(11 "B.Adhes" user "B.Adhesive")
		(13 "F.Paste" user "Package Geometry/Pastemask Top")
		(15 "B.Paste" user "Package Geometry/Pastemask Bottom")
		(5 "F.SilkS" user "Ref Des/Silkscreen Top")
		(7 "B.SilkS" user "Ref Des/Silkscreen Bottom")
		(1 "F.Mask" user "Board Geometry/Soldermask Top")
		(3 "B.Mask" user "Board Geometry/Soldermask Bottom")
		(17 "Dwgs.User" user "User.Drawings")
		(19 "Cmts.User" user "User.Comments")
		(21 "Eco1.User" user "User.Eco1")
		(23 "Eco2.User" user "User.Eco2")
		(25 "Edge.Cuts" user "Board Geometry/Outline")
		(27 "Margin" user)
		(31 "F.CrtYd" user "Package Geometry/Place Bound Top")
		(29 "B.CrtYd" user "Package Geometry/Place Bound Bottom")
		(35 "F.Fab" user "Ref Des/Assembly Top")
		(33 "B.Fab" user "Ref Des/Assembly Bottom")
	)
	(footprint ""
		(layer "F.Cu")
		(at 200.035668 -78.42377 180)
		(property "Reference" "R73"
			(at 0 0 180)
			(layer "F.SilkS")
			(hide yes)
			(effects
				(font
					(size 1.27 1.27)
				)
			)
		)
		(property "Value" ""
			(at 0 0 180)
			(layer "F.Fab")
			(effects
				(font
					(size 1.27 1.27)
				)
			)
		)
		(duplicate_pad_numbers_are_jumpers no)
		(fp_line
			(start 0.7874 0.4064)
			(end -0.7874 0.4064)
			(stroke
				(width 0.1524)
				(type default)
			)
			(layer "F.SilkS")
		)
		(fp_line
			(start 0.7874 -0.4064)
			(end 0.7874 0.4064)
			(stroke
				(width 0.1524)
				(type default)
			)
			(layer "F.SilkS")
		)
		(fp_line
			(start -0.7874 0.4064)
			(end -0.7874 -0.4064)
			(stroke
				(width 0.1524)
				(type default)
			)
			(layer "F.SilkS")
		)
		(fp_line
			(start -0.7874 -0.4064)
			(end 0.7874 -0.4064)
			(stroke
				(width 0.1524)
				(type default)
			)
			(layer "F.SilkS")
		)
		(fp_line
			(start 0.67945 0.3048)
			(end 0.120396 0.3048)
			(stroke
				(width 0.1)
				(type default)
			)
			(layer "F.Fab")
		)
		(fp_line
			(start 0.67945 -0.3048)
			(end 0.67945 0.3048)
			(stroke
				(width 0.1)
				(type default)
			)
			(layer "F.Fab")
		)
		(fp_line
			(start 0.12065 -0.2794)
			(end 0.12065 -0.3048)
			(stroke
				(width 0.1)
				(type default)
			)
			(layer "F.Fab")
		)
		(fp_line
			(start 0.12065 -0.3048)
			(end 0.67945 -0.3048)
			(stroke
				(width 0.1)
				(type default)
			)
			(layer "F.Fab")
		)
		(fp_line
			(start 0.120396 0.3048)
			(end 0.120396 0.2794)
			(stroke
				(width 0.1)
				(type default)
			)
			(layer "F.Fab")
		)
		(fp_line
			(start 0.120396 0.2794)
			(end -0.12065 0.2794)
			(stroke
				(width 0.1)
				(type default)
			)
			(layer "F.Fab")
		)
		(fp_line
			(start -0.12065 0.3048)
			(end -0.67945 0.3048)
			(stroke
				(width 0.1)
				(type default)
			)
			(layer "F.Fab")
		)
		(fp_line
			(start -0.12065 0.2794)
			(end -0.12065 0.3048)
			(stroke
				(width 0.1)
				(type default)
			)
			(layer "F.Fab")
		)
		(fp_line
			(start -0.12065 -0.2794)
			(end 0.12065 -0.2794)
			(stroke
				(width 0.1)
				(type default)
			)
			(layer "F.Fab")
		)
		(fp_line
			(start -0.12065 -0.305054)
			(end -0.12065 -0.2794)
			(stroke
				(width 0.1)
				(type default)
			)
			(layer "F.Fab")
		)
		(fp_line
			(start -0.67945 0.3048)
			(end -0.67945 -0.305054)
			(stroke
				(width 0.1)
				(type default)
			)
			(layer "F.Fab")
		)
		(fp_line
			(start -0.67945 -0.305054)
			(end -0.12065 -0.305054)
			(stroke
				(width 0.1)
				(type default)
			)
			(layer "F.Fab")
		)
		(pad "1" smd circle
			(at -0.40005 0 180)
			(size 0 0)
			(layers "F.Cu" "F.Mask" "F.Paste")
			(net "NCSI_BMC_RXD1_R")
		)
		(pad "2" smd circle
			(at 0.40005 0 180)
			(size 0 0)
			(layers "F.Cu" "F.Mask" "F.Paste")
			(net "RMII_OCP_BMC_RXD_1")
		)
	)
	(footprint ""
		(layer "F.Cu")
		(at 118.5164 -36.67125 90)
		(property "Reference" "R6270"
			(at 0 0 90)
			(layer "F.SilkS")
			(hide yes)
			(effects
				(font
					(size 1.27 1.27)
				)
			)
		)
		(property "Value" ""
			(at 0 0 90)
			(layer "F.Fab")
			(effects
				(font
					(size 1.27 1.27)
				)
			)
		)
		(duplicate_pad_numbers_are_jumpers no)
		(fp_line
			(start 0.7874 -0.4064)
			(end 0.7874 0.4064)
			(stroke
				(width 0.1524)
				(type default)
			)
			(layer "F.SilkS")
		)
		(fp_line
			(start -0.7874 -0.4064)
			(end 0.7874 -0.4064)
			(stroke
				(width 0.1524)
				(type default)
			)
			(layer "F.SilkS")
		)
		(fp_line
			(start 0.7874 0.4064)
			(end -0.7874 0.4064)
			(stroke
				(width 0.1524)
				(type default)
			)
			(layer "F.SilkS")
		)
		(fp_line
			(start -0.7874 0.4064)
			(end -0.7874 -0.4064)
			(stroke
				(width 0.1524)
				(type default)
			)
			(layer "F.SilkS")
		)
		(fp_line
			(start -0.12065 -0.305054)
			(end -0.12065 -0.2794)
			(stroke
				(width 0.1)
				(type default)
			)
			(layer "F.Fab")
		)
		(fp_line
			(start -0.67945 -0.305054)
			(end -0.12065 -0.305054)
			(stroke
				(width 0.1)
				(type default)
			)
			(layer "F.Fab")
		)
		(fp_line
			(start 0.67945 -0.3048)
			(end 0.67945 0.3048)
			(stroke
				(width 0.1)
				(type default)
			)
			(layer "F.Fab")
		)
		(fp_line
			(start 0.12065 -0.3048)
			(end 0.67945 -0.3048)
			(stroke
				(width 0.1)
				(type default)
			)
			(layer "F.Fab")
		)
		(fp_line
			(start 0.12065 -0.2794)
			(end 0.12065 -0.3048)
			(stroke
				(width 0.1)
				(type default)
			)
			(layer "F.Fab")
		)
		(fp_line
			(start -0.12065 -0.2794)
			(end 0.12065 -0.2794)
			(stroke
				(width 0.1)
				(type default)
			)
			(layer "F.Fab")
		)
		(fp_line
			(start 0.120396 0.2794)
			(end -0.12065 0.2794)
			(stroke
				(width 0.1)
				(type default)
			)
			(layer "F.Fab")
		)
		(fp_line
			(start -0.12065 0.2794)
			(end -0.12065 0.3048)
			(stroke
				(width 0.1)
				(type default)
			)
			(layer "F.Fab")
		)
		(fp_line
			(start 0.67945 0.3048)
			(end 0.120396 0.3048)
			(stroke
				(width 0.1)
				(type default)
			)
			(layer "F.Fab")
		)
		(fp_line
			(start 0.120396 0.3048)
			(end 0.120396 0.2794)
			(stroke
				(width 0.1)
				(type default)
			)
			(layer "F.Fab")
		)
		(fp_line
			(start -0.12065 0.3048)
			(end -0.67945 0.3048)
			(stroke
				(width 0.1)
				(type default)
			)
			(layer "F.Fab")
		)
		(fp_line
			(start -0.67945 0.3048)
			(end -0.67945 -0.305054)
			(stroke
				(width 0.1)
				(type default)
			)
			(layer "F.Fab")
		)
		(pad "1" smd circle
			(at -0.40005 0 90)
			(size 0 0)
			(layers "F.Cu" "F.Mask" "F.Paste")
			(net "P3V3_AUX_CPU0_USB2_AVDD33")
		)
		(pad "2" smd circle
			(at 0.40005 0 90)
			(size 0 0)
			(layers "F.Cu" "F.Mask" "F.Paste")
			(net "USB_HUB2_TI_PWRCTL3_MRP_VDD33")
		)
	)
)
